# SCM (Grand Teton) — schematic netlist excerpt (pin names and nets, part order shuffled) for the footprints in the layout excerpt that follows; sources: Cadence DE-HDL packaged netlist, KiCad conversion of 12092022_DA0F0TMDCD0_F0T_Management_Board_D_brd_V3_OCP.brd

C109  Q_CAP  0.1UF 25V 10% X7R  pkg 0402  page 16 : A = P1V8_AUX ; B = GND
R248  Q_RES  2.2K 5% CHIP  pkg 0402LF  page 27 : A = P3V3_AUX ; B = SMB_BMC_MM3_SCL

(kicad_pcb
	(version 20260206)
	(generator "pcbnew")
	(generator_version "10.0")
	(general
		(thickness 1.6)
		(legacy_teardrops no)
	)
	(paper "A4")
	(title_block
		(title "12092022_DA0F0TMDCD0_F0T_Management_Board_D_brd_V3_OCP.brd")
		(comment 1 "Grand Teton / footprints 1197-1198 of 1440")
	)
	(layers
		(0 "F.Cu" signal "TOP")
		(4 "In1.Cu" signal "GND")
		(6 "In2.Cu" signal "IN1")
		(8 "In3.Cu" signal "GND1")
		(10 "In4.Cu" signal "IN2")
		(12 "In5.Cu" signal "VCC")
		(14 "In6.Cu" signal "VCC1")
		(16 "In7.Cu" signal "IN3")
		(18 "In8.Cu" signal "GND2")
		(20 "In9.Cu" signal "IN4")
		(22 "In10.Cu" signal "GND3")
		(2 "B.Cu" signal "BOTTOM")
		(9 "F.Adhes" user "F.Adhesive")
		(11 "B.Adhes" user "B.Adhesive")
		(13 "F.Paste" user "Package Geometry/Pastemask Top")
		(15 "B.Paste" user "Package Geometry/Pastemask Bottom")
		(5 "F.SilkS" user "Ref Des/Silkscreen Top")
		(7 "B.SilkS" user "Ref Des/Silkscreen Bottom")
		(1 "F.Mask" user "Board Geometry/Soldermask Top")
		(3 "B.Mask" user "Board Geometry/Soldermask Bottom")
		(17 "Dwgs.User" user "User.Drawings")
		(19 "Cmts.User" user "User.Comments")
		(21 "Eco1.User" user "User.Eco1")
		(23 "Eco2.User" user "User.Eco2")
		(25 "Edge.Cuts" user "Board Geometry/Outline")
		(27 "Margin" user)
		(31 "F.CrtYd" user "Package Geometry/Place Bound Top")
		(29 "B.CrtYd" user "Package Geometry/Place Bound Bottom")
		(35 "F.Fab" user "Ref Des/Assembly Top")
		(33 "B.Fab" user "Ref Des/Assembly Bottom")
	)
	(footprint ""
		(layer "B.Cu")
		(at 47.607474 -30.857698 -90)
		(property "Reference" "R248"
			(at 0 0 90)
			(layer "B.SilkS")
			(hide yes)
			(effects
				(font
					(size 1.27 1.27)
				)
				(justify mirror)
			)
		)
		(property "Value" ""
			(at 0 0 90)
			(layer "B.Fab")
			(effects
				(font
					(size 1.27 1.27)
				)
				(justify mirror)
			)
		)
		(duplicate_pad_numbers_are_jumpers no)
		(fp_line
			(start -0.7874 0.4064)
			(end 0.7874 0.4064)
			(stroke
				(width 0.1524)
				(type default)
			)
			(layer "B.SilkS")
		)
		(fp_line
			(start 0.7874 0.4064)
			(end 0.7874 -0.4064)
			(stroke
				(width 0.1524)
				(type default)
			)
			(layer "B.SilkS")
		)
		(fp_line
			(start -0.7874 -0.4064)
			(end -0.7874 0.4064)
			(stroke
				(width 0.1524)
				(type default)
			)
			(layer "B.SilkS")
		)
		(fp_line
			(start 0.7874 -0.4064)
			(end -0.7874 -0.4064)
			(stroke
				(width 0.1524)
				(type default)
			)
			(layer "B.SilkS")
		)
		(fp_line
			(start -0.67945 0.3048)
			(end -0.120396 0.3048)
			(stroke
				(width 0.1)
				(type default)
			)
			(layer "B.Fab")
		)
		(fp_line
			(start -0.120396 0.3048)
			(end -0.120396 0.2794)
			(stroke
				(width 0.1)
				(type default)
			)
			(layer "B.Fab")
		)
		(fp_line
			(start 0.12065 0.3048)
			(end 0.67945 0.3048)
			(stroke
				(width 0.1)
				(type default)
			)
			(layer "B.Fab")
		)
		(fp_line
			(start 0.67945 0.3048)
			(end 0.67945 -0.305054)
			(stroke
				(width 0.1)
				(type default)
			)
			(layer "B.Fab")
		)
		(fp_line
			(start -0.120396 0.2794)
			(end 0.12065 0.2794)
			(stroke
				(width 0.1)
				(type default)
			)
			(layer "B.Fab")
		)
		(fp_line
			(start 0.12065 0.2794)
			(end 0.12065 0.3048)
			(stroke
				(width 0.1)
				(type default)
			)
			(layer "B.Fab")
		)
		(fp_line
			(start -0.12065 -0.2794)
			(end -0.12065 -0.3048)
			(stroke
				(width 0.1)
				(type default)
			)
			(layer "B.Fab")
		)
		(fp_line
			(start 0.12065 -0.2794)
			(end -0.12065 -0.2794)
			(stroke
				(width 0.1)
				(type default)
			)
			(layer "B.Fab")
		)
		(fp_line
			(start -0.67945 -0.3048)
			(end -0.67945 0.3048)
			(stroke
				(width 0.1)
				(type default)
			)
			(layer "B.Fab")
		)
		(fp_line
			(start -0.12065 -0.3048)
			(end -0.67945 -0.3048)
			(stroke
				(width 0.1)
				(type default)
			)
			(layer "B.Fab")
		)
		(fp_line
			(start 0.12065 -0.305054)
			(end 0.12065 -0.2794)
			(stroke
				(width 0.1)
				(type default)
			)
			(layer "B.Fab")
		)
		(fp_line
			(start 0.67945 -0.305054)
			(end 0.12065 -0.305054)
			(stroke
				(width 0.1)
				(type default)
			)
			(layer "B.Fab")
		)
		(pad "1" smd circle
			(at 0.40005 0 90)
			(size 0 0)
			(layers "B.Cu" "B.Mask" "B.Paste")
			(net "P3V3_AUX")
		)
		(pad "2" smd circle
			(at -0.40005 0 90)
			(size 0 0)
			(layers "B.Cu" "B.Mask" "B.Paste")
			(net "SMB_BMC_MM3_SCL")
		)
	)
	(footprint ""
		(layer "B.Cu")
		(at 56.695848 -49.246028)
		(property "Reference" "C109"
			(at 0 0 0)
			(layer "B.SilkS")
			(hide yes)
			(effects
				(font
					(size 1.27 1.27)
				)
				(justify mirror)
			)
		)
		(property "Value" ""
			(at 0 0 0)
			(layer "B.Fab")
			(effects
				(font
					(size 1.27 1.27)
				)
				(justify mirror)
			)
		)
		(duplicate_pad_numbers_are_jumpers no)
		(fp_line
			(start -0.7874 -0.4064)
			(end -0.7874 0.4064)
			(stroke
				(width 0.1524)
				(type default)
			)
			(layer "B.SilkS")
		)
		(fp_line
			(start -0.7874 0.4064)
			(end 0.7874 0.4064)
			(stroke
				(width 0.1524)
				(type default)
			)
			(layer "B.SilkS")
		)
		(fp_line
			(start 0.7874 -0.4064)
			(end -0.7874 -0.4064)
			(stroke
				(width 0.1524)
				(type default)
			)
			(layer "B.SilkS")
		)
		(fp_line
			(start 0.7874 0.4064)
			(end 0.7874 -0.4064)
			(stroke
				(width 0.1524)
				(type default)
			)
			(layer "B.SilkS")
		)
		(fp_line
			(start -0.67945 -0.3048)
			(end -0.67945 0.3048)
			(stroke
				(width 0.1)
				(type default)
			)
			(layer "B.Fab")
		)
		(fp_line
			(start -0.67945 0.3048)
			(end -0.120396 0.3048)
			(stroke
				(width 0.1)
				(type default)
			)
			(layer "B.Fab")
		)
		(fp_line
			(start -0.12065 -0.3048)
			(end -0.67945 -0.3048)
			(stroke
				(width 0.1)
				(type default)
			)
			(layer "B.Fab")
		)
		(fp_line
			(start -0.12065 -0.2794)
			(end -0.12065 -0.3048)
			(stroke
				(width 0.1)
				(type default)
			)
			(layer "B.Fab")
		)
		(fp_line
			(start -0.120396 0.2794)
			(end 0.12065 0.2794)
			(stroke
				(width 0.1)
				(type default)
			)
			(layer "B.Fab")
		)
		(fp_line
			(start -0.120396 0.3048)
			(end -0.120396 0.2794)
			(stroke
				(width 0.1)
				(type default)
			)
			(layer "B.Fab")
		)
		(fp_line
			(start 0.12065 -0.305054)
			(end 0.12065 -0.2794)
			(stroke
				(width 0.1)
				(type default)
			)
			(layer "B.Fab")
		)
		(fp_line
			(start 0.12065 -0.2794)
			(end -0.12065 -0.2794)
			(stroke
				(width 0.1)
				(type default)
			)
			(layer "B.Fab")
		)
		(fp_line
			(start 0.12065 0.2794)
			(end 0.12065 0.3048)
			(stroke
				(width 0.1)
				(type default)
			)
			(layer "B.Fab")
		)
		(fp_line
			(start 0.12065 0.3048)
			(end 0.67945 0.3048)
			(stroke
				(width 0.1)
				(type default)
			)
			(layer "B.Fab")
		)
		(fp_line
			(start 0.67945 -0.305054)
			(end 0.12065 -0.305054)
			(stroke
				(width 0.1)
				(type default)
			)
			(layer "B.Fab")
		)
		(fp_line
			(start 0.67945 0.3048)
			(end 0.67945 -0.305054)
			(stroke
				(width 0.1)
				(type default)
			)
			(layer "B.Fab")
		)
		(pad "1" smd circle
			(at 0.40005 0 180)
			(size 0 0)
			(layers "B.Cu" "B.Mask" "B.Paste")
			(net "P1V8_AUX")
		)
		(pad "2" smd circle
			(at -0.40005 0 180)
			(size 0 0)
			(layers "B.Cu" "B.Mask" "B.Paste")
			(net "GND")
		)
	)
)
